# S9S_MB_2U (Grand Teton) — schematic netlist excerpt (pin names and nets, part order shuffled) for the footprints in the layout excerpt that follows; sources: Cadence DE-HDL packaged netlist, KiCad conversion of 03242023_DA0F0TMBIJ0_F0T_Motherboard_J_brd_V01_OCP.brd

J9  SCONN288_ADR50017P130CC  SCONN288_ADR50017-P130CC IO  pkg DDR288S_1-1VXB  page 90
  VIN_BULK0  = P12V_S3_AUX_CPU0_NVDIMM
  RFU0  = TP_CHE_CPU0_DIMM1_FRU_0
  VIN_MGMT  = P3V3_AUX
  HSCL  = I3C_SPD_DDREFGH_CPU0_LVC1_SCL_R
  HSDA  = I3C_SPD_DDREFGH_CPU0_LVC1_SDA
  VSS0  = GND
  DQ0_A  = M_E_CPU0_SA_DQ<0>
  VSS1  = GND
  DQ1_A  = M_E_CPU0_SA_DQ<1>
  VSS2  = GND
  DQS0_A_T  = M_E_CPU0_SA_DQS_DP<0>
  DQS0_A_C  = M_E_CPU0_SA_DQS_DN<0>
  VSS3  = GND
  DQ4_A  = M_E_CPU0_SA_DQ<4>
  VSS4  = GND
  DQ5_A  = M_E_CPU0_SA_DQ<5>
  VSS5  = GND
  DQ8_A  = M_E_CPU0_SA_DQ<8>
  VSS6  = GND
  DQ9_A  = M_E_CPU0_SA_DQ<9>
  VSS7  = GND
  DQS1_A_T  = M_E_CPU0_SA_DQS_DP<1>
  DQS1_A_C  = M_E_CPU0_SA_DQS_DN<1>
  VSS8  = GND
  DQ12_A  = M_E_CPU0_SA_DQ<12>
  VSS9  = GND
  DQ13_A  = M_E_CPU0_SA_DQ<13>
  VSS10  = GND
  DQ16_A  = M_E_CPU0_SA_DQ<16>
  VSS11  = GND
  DQ17_A  = M_E_CPU0_SA_DQ<17>
  VSS12  = GND
  DQS2_A_T  = M_E_CPU0_SA_DQS_DP<2>
  DQS2_A_C  = M_E_CPU0_SA_DQS_DN<2>
  VSS13  = GND
  DQ20_A  = M_E_CPU0_SA_DQ<20>
  VSS14  = GND
  DQ21_A  = M_E_CPU0_SA_DQ<21>
  VSS15  = GND
  DQ24_A  = M_E_CPU0_SA_DQ<24>
  VSS16  = GND
  DQ25_A  = M_E_CPU0_SA_DQ<25>
  VSS17  = GND
  DQS3_A_T  = M_E_CPU0_SA_DQS_DP<3>
  DQS3_A_C  = M_E_CPU0_SA_DQS_DN<3>
  VSS18  = GND
  DQ28_A  = M_E_CPU0_SA_DQ<28>
  VSS19  = GND
  DQ29_A  = M_E_CPU0_SA_DQ<29>
  VSS20  = GND
  CB0_A  = M_E_CPU0_SA_CB<0>
  VSS21  = GND
  CB1_A  = M_E_CPU0_SA_CB<1>
  VSS22  = GND
  DQS4_A_T  = M_E_CPU0_SA_DQS_DP<4>
  DQS4_A_C  = M_E_CPU0_SA_DQS_DN<4>
  VSS23  = GND
  CB4_A  = M_E_CPU0_SA_CB<4>
  VSS24  = GND
  CB5_A  = M_E_CPU0_SA_CB<5>
  VSS25  = GND
  ALERT_N  = M_E_CPU0_ALERT_N
  VSS26  = GND
  CS0_A_N  = M_E_CPU0_SA_CS_N<0>
  VSS27  = GND
  CA0_A  = M_E_CPU0_SA_CA<0>
  VSS28  = GND
  CA2_A  = M_E_CPU0_SA_CA<2>
  VSS29  = GND
  CA4_A  = M_E_CPU0_SA_CA<4>
  VSS30  = GND
  CA6_A  = M_E_CPU0_SA_CA<6>
  VSS31  = GND
  PAR_A  = M_E_CPU0_SA_PAR
  VSS32  = GND
  CA0_B  = M_E_CPU0_SB_CA<0>
  VSS33  = GND
  CA2_B  = M_E_CPU0_SB_CA<2>
  VSS34  = GND
  CA4_B  = M_E_CPU0_SB_CA<4>
  VSS35  = GND
  CA6_B  = M_E_CPU0_SB_CA<6>
  VSS36  = GND
  CS0_B_N  = M_E_CPU0_SB_CS_N<0>
  VSS37  = GND
  \lbd||rsp_a_n\  = M_E_CPU0_SA_RSP<0>
  \lbs||rsp_b_n\  = M_E_CPU0_SB_RSP<0>
  VSS38  = GND
  CB4_B  = M_E_CPU0_SB_CB<4>
  VSS39  = GND
  CB5_B  = M_E_CPU0_SB_CB<5>
  VSS40  = GND
  \dqs9_b_t||tdqs9_b_t||dbi4_b_n\  = M_E_CPU0_SB_DQS_DP<9>
  \dqs9_b_c||tdqs9_b_c\  = M_E_CPU0_SB_DQS_DN<9>
  VSS41  = GND
  CB0_B  = M_E_CPU0_SB_CB<0>
  VSS42  = GND
  CB1_B  = M_E_CPU0_SB_CB<1>
  VSS43  = GND
  DQ0_B  = M_E_CPU0_SB_DQ<0>
  VSS44  = GND
  DQ1_B  = M_E_CPU0_SB_DQ<1>
  VSS45  = GND
  DQS0_B_T  = M_E_CPU0_SB_DQS_DP<0>
  DQS0_B_C  = M_E_CPU0_SB_DQS_DN<0>
  VSS46  = GND
  DQ4_B  = M_E_CPU0_SB_DQ<4>
  VSS47  = GND
  DQ5_B  = M_E_CPU0_SB_DQ<5>
  VSS48  = GND
  DQ8_B  = M_E_CPU0_SB_DQ<8>
  VSS49  = GND
  DQ9_B  = M_E_CPU0_SB_DQ<9>
  VSS50  = GND
  DQS1_B_T  = M_E_CPU0_SB_DQS_DP<1>
  DQS1_B_C  = M_E_CPU0_SB_DQS_DN<1>
  VSS51  = GND
  DQ12_B  = M_E_CPU0_SB_DQ<12>
  VSS52  = GND
  DQ13_B  = M_E_CPU0_SB_DQ<13>
  VSS53  = GND
  DQ16_B  = M_E_CPU0_SB_DQ<16>
  VSS54  = GND
  DQ17_B  = M_E_CPU0_SB_DQ<17>
  VSS55  = GND
  DQS2_B_T  = M_E_CPU0_SB_DQS_DP<2>
  DQS2_B_C  = M_E_CPU0_SB_DQS_DN<2>
  VSS56  = GND
  DQ20_B  = M_E_CPU0_SB_DQ<20>
  VSS57  = GND
  DQ21_B  = M_E_CPU0_SB_DQ<21>
  VSS58  = GND
  DQ24_B  = M_E_CPU0_SB_DQ<24>
  VSS59  = GND
  DQ25_B  = M_E_CPU0_SB_DQ<25>
  VSS60  = GND
  DQS3_B_T  = M_E_CPU0_SB_DQS_DP<3>
  DQS3_B_C  = M_E_CPU0_SB_DQS_DN<3>
  VSS61  = GND
  DQ28_B  = M_E_CPU0_SB_DQ<28>
  VSS62  = GND
  DQ29_B  = M_E_CPU0_SB_DQ<29>
  VSS63  = GND
  RFU1  = TP_CHE_CPU0_DIMM1_FRU_1
  VIN_BULK1  = P12V_S3_AUX_CPU0_NVDIMM
  VIN_BULK2  = P12V_S3_AUX_CPU0_NVDIMM
  \pwr_good||fail_n\  = PWRGD_CHE_CPU0_DIMM1
  HSA  = PD_CHE_CPU0_DIMM1_SAA
  RFU2  = TP_CHE_CPU0_DIMM1_FRU_2
  RFU3  = TP_CHE_CPU0_DIMM1_FRU_3
  VSS64  = GND
  DQ2_A  = M_E_CPU0_SA_DQ<2>
  VSS65  = GND
  DQ3_A  = M_E_CPU0_SA_DQ<3>
  VSS66  = GND
  \dqs5_a_c||tdqs5_a_c||dqs5_a_t||tdqs5_a_t\  = M_E_CPU0_SA_DQS_DN<5>
  \dqs5_a_t||tdqs5_a_t\  = M_E_CPU0_SA_DQS_DP<5>
  VSS67  = GND
  DQ6_A  = M_E_CPU0_SA_DQ<6>
  VSS68  = GND
  DQ7_A  = M_E_CPU0_SA_DQ<7>
  VSS69  = GND
  DQ10_A  = M_E_CPU0_SA_DQ<10>
  VSS70  = GND
  DQ11_A  = M_E_CPU0_SA_DQ<11>
  VSS71  = GND
  \dqs6_a_c||tdqs6_a_c||dqs6_a_t||tdqs6_a_t\  = M_E_CPU0_SA_DQS_DN<6>
  \dqs6_a_t||tdqs6_a_t\  = M_E_CPU0_SA_DQS_DP<6>
  VSS72  = GND
  DQ14_A  = M_E_CPU0_SA_DQ<14>
  VSS73  = GND
  DQ15_A  = M_E_CPU0_SA_DQ<15>
  VSS74  = GND
  DQ18_A  = M_E_CPU0_SA_DQ<18>
  VSS75  = GND
  DQ19_A  = M_E_CPU0_SA_DQ<19>
  VSS76  = GND
  \dqs7_a_c||tdqs7_a_c\  = M_E_CPU0_SA_DQS_DN<7>
  \dqs7_a_t||tdqs7_a_t\  = M_E_CPU0_SA_DQS_DP<7>
  VSS77  = GND
  DQ22_A  = M_E_CPU0_SA_DQ<22>
  VSS78  = GND
  DQ23_A  = M_E_CPU0_SA_DQ<23>
  VSS79  = GND
  DQ26_A  = M_E_CPU0_SA_DQ<26>
  VSS80  = GND
  DQ27_A  = M_E_CPU0_SA_DQ<27>
  VSS81  = GND
  \dqs8_a_c||tdqs8_a_c\  = M_E_CPU0_SA_DQS_DN<8>
  \dqs8_a_t||tdqs8_a_t\  = M_E_CPU0_SA_DQS_DP<8>
  VSS82  = GND
  DQ30_A  = M_E_CPU0_SA_DQ<30>
  VSS83  = GND
  DQ31_A  = M_E_CPU0_SA_DQ<31>
  VSS84  = GND
  CB2_A  = M_E_CPU0_SA_CB<2>
  VSS85  = GND
  CB3_A  = M_E_CPU0_SA_CB<3>
  VSS86  = GND
  \dqs9_a_c||tdqs9_a_c\  = M_E_CPU0_SA_DQS_DN<9>
  \dqs9_a_t||tdqs9_a_t\  = M_E_CPU0_SA_DQS_DP<9>
  VSS87  = GND
  CB6_A  = M_E_CPU0_SA_CB<6>
  VSS88  = GND
  CB7_A  = M_E_CPU0_SA_CB<7>
  VSS89  = GND
  RESET_N  = RST_M_EF_CPU0_FPGA_N
  VSS90  = GND
  CS1_A_N  = M_E_CPU0_SA_CS_N<1>
  VSS91  = GND
  CA1_A  = M_E_CPU0_SA_CA<1>
  VSS92  = GND
  CA3_A  = M_E_CPU0_SA_CA<3>
  VSS93  = GND
  CA5_A  = M_E_CPU0_SA_CA<5>
  VSS94  = GND
  CK_T  = M_E_CPU0_CLK_DP<0>
  CK_C  = M_E_CPU0_CLK_DN<0>
  VSS95  = GND
  RFU4  = TP_CHE_CPU0_DIMM1_FRU_4
  CA1_B  = M_E_CPU0_SB_CA<1>
  VSS96  = GND
  CA3_B  = M_E_CPU0_SB_CA<3>
  VSS97  = GND
  CA5_B  = M_E_CPU0_SB_CA<5>
  VSS98  = GND
  PAR_B  = M_E_CPU0_SB_PAR
  VSS99  = GND
  CS1_B_N  = M_E_CPU0_SB_CS_N<1>
  VSS100  = GND
  RFU5  = TP_CHE_CPU0_DIMM1_FRU_5
  RFU6  = TP_CHE_CPU0_DIMM1_FRU_6
  VSS101  = GND
  CB6_B  = M_E_CPU0_SB_CB<6>
  VSS102  = GND
  CB7_B  = M_E_CPU0_SB_CB<7>
  VSS103  = GND
  DQS4_B_C  = M_E_CPU0_SB_DQS_DN<4>
  DQS4_B_T  = M_E_CPU0_SB_DQS_DP<4>
  VSS104  = GND
  CB2_B  = M_E_CPU0_SB_CB<2>
  VSS105  = GND
  CB3_B  = M_E_CPU0_SB_CB<3>
  VSS106  = GND
  DQ2_B  = M_E_CPU0_SB_DQ<2>
  VSS107  = GND
  DQ3_B  = M_E_CPU0_SB_DQ<3>
  VSS108  = GND
  \dqs5_b_c||tdqs5_b_c\  = M_E_CPU0_SB_DQS_DN<5>
  \dqs5_b_t||tdqs5_b_t\  = M_E_CPU0_SB_DQS_DP<5>
  VSS109  = GND
  DQ6_B  = M_E_CPU0_SB_DQ<6>
  VSS110  = GND
  DQ7_B  = M_E_CPU0_SB_DQ<7>
  VSS111  = GND
  DQ10_B  = M_E_CPU0_SB_DQ<10>
  VSS112  = GND
  DQ11_B  = M_E_CPU0_SB_DQ<11>
  VSS113  = GND
  \dqs6_b_c||tdqs6_b_c\  = M_E_CPU0_SB_DQS_DN<6>
  \dqs6_b_t||tdqs6_b_t\  = M_E_CPU0_SB_DQS_DP<6>
  VSS114  = GND
  DQ14_B  = M_E_CPU0_SB_DQ<14>
  VSS115  = GND
  DQ15_B  = M_E_CPU0_SB_DQ<15>
  VSS116  = GND
  DQ18_B  = M_E_CPU0_SB_DQ<18>
  VSS117  = GND
  DQ19_B  = M_E_CPU0_SB_DQ<19>
  VSS118  = GND
  \dqs7_b_c||tdqs7_b_c\  = M_E_CPU0_SB_DQS_DN<7>
  \dqs7_b_t||tdqs7_b_t\  = M_E_CPU0_SB_DQS_DP<7>
  VSS119  = GND
  DQ22_B  = M_E_CPU0_SB_DQ<22>
  VSS120  = GND
  DQ23_B  = M_E_CPU0_SB_DQ<23>
  VSS121  = GND
  DQ26_B  = M_E_CPU0_SB_DQ<26>
  VSS122  = GND
  DQ27_B  = M_E_CPU0_SB_DQ<27>
  VSS123  = GND
  \dqs8_b_c||tdqs8_b_c\  = M_E_CPU0_SB_DQS_DN<8>
  \dqs8_b_t||tdqs8_b_t\  = M_E_CPU0_SB_DQS_DP<8>
  VSS124  = GND
  DQ30_B  = M_E_CPU0_SB_DQ<30>
  VSS125  = GND
  DQ31_B  = M_E_CPU0_SB_DQ<31>
  VSS126  = GND
  G1  = GND
  G2  = GND
  G3  = GND

(kicad_pcb
	(version 20260206)
	(generator "pcbnew")
	(generator_version "10.0")
	(general
		(thickness 1.6)
		(legacy_teardrops no)
	)
	(paper "A4")
	(title_block
		(title "03242023_DA0F0TMBIJ0_F0T_Motherboard_J_brd_V01_OCP.brd")
		(comment 1 "Grand Teton / footprint 461 of 6105 (J9), pads 46-91 of 291")
	)
	(layers
		(0 "F.Cu" signal "TOP")
		(4 "In1.Cu" signal "GND")
		(6 "In2.Cu" signal "IN1")
		(8 "In3.Cu" signal "GND1")
		(10 "In4.Cu" signal "IN2")
		(12 "In5.Cu" signal "GND2")
		(14 "In6.Cu" signal "IN3")
		(16 "In7.Cu" signal "GND3")
		(18 "In8.Cu" signal "VCC")
		(20 "In9.Cu" signal "VCC1")
		(22 "In10.Cu" signal "GND4")
		(24 "In11.Cu" signal "IN4")
		(26 "In12.Cu" signal "GND5")
		(28 "In13.Cu" signal "IN5")
		(30 "In14.Cu" signal "GND6")
		(32 "In15.Cu" signal "IN6")
		(34 "In16.Cu" signal "GND7")
		(2 "B.Cu" signal "BOTTOM")
		(9 "F.Adhes" user "F.Adhesive")
		(11 "B.Adhes" user "B.Adhesive")
		(13 "F.Paste" user "Package Geometry/Pastemask Top")
		(15 "B.Paste" user "Package Geometry/Pastemask Bottom")
		(5 "F.SilkS" user "Ref Des/Silkscreen Top")
		(7 "B.SilkS" user "Ref Des/Silkscreen Bottom")
		(1 "F.Mask" user "Board Geometry/Soldermask Top")
		(3 "B.Mask" user "Board Geometry/Soldermask Bottom")
		(17 "Dwgs.User" user "User.Drawings")
		(19 "Cmts.User" user "User.Comments")
		(21 "Eco1.User" user "User.Eco1")
		(23 "Eco2.User" user "User.Eco2")
		(25 "Edge.Cuts" user "Board Geometry/Outline")
		(27 "Margin" user)
		(31 "F.CrtYd" user "Package Geometry/Place Bound Top")
		(29 "B.CrtYd" user "Package Geometry/Place Bound Bottom")
		(35 "F.Fab" user "Ref Des/Assembly Top")
		(33 "B.Fab" user "Ref Des/Assembly Bottom")
	)
	(footprint ""
		(layer "F.Cu")
		(at 416.347148 -258.091686)
		(property "Reference" "J9"
			(at -3.683 -81.702148 0)
			(unlocked yes)
			(layer "F.SilkS")
			(effects
				(font
					(size 0.7874 0.5842)
					(thickness 0.1524)
				)
				(justify left)
			)
		)
		(property "Value" ""
			(at 0 0 0)
			(layer "F.Fab")
			(effects
				(font
					(size 1.27 1.27)
				)
			)
		)
		(duplicate_pad_numbers_are_jumpers no)
		(pad "46" smd rect
			(at -2.050034 -25.07488 270)
			(size 0.519938 1.4986)
			(layers "F.Cu" "F.Mask" "F.Paste")
			(net "GND")
		)
		(pad "47" smd rect
			(at -2.050034 -24.224996 270)
			(size 0.519938 1.4986)
			(layers "F.Cu" "F.Mask" "F.Paste")
			(net "M_E_CPU0_SA_DQ<28>")
		)
		(pad "48" smd rect
			(at -2.050034 -23.375112 270)
			(size 0.519938 1.4986)
			(layers "F.Cu" "F.Mask" "F.Paste")
			(net "GND")
		)
		(pad "49" smd rect
			(at -2.050034 -22.524974 270)
			(size 0.519938 1.4986)
			(layers "F.Cu" "F.Mask" "F.Paste")
			(net "M_E_CPU0_SA_DQ<29>")
		)
		(pad "50" smd rect
			(at -2.050034 -21.67509 270)
			(size 0.519938 1.4986)
			(layers "F.Cu" "F.Mask" "F.Paste")
			(net "GND")
		)
		(pad "51" smd rect
			(at -2.050034 -20.824952 270)
			(size 0.519938 1.4986)
			(layers "F.Cu" "F.Mask" "F.Paste")
			(net "M_E_CPU0_SA_CB<0>")
		)
		(pad "52" smd rect
			(at -2.050034 -19.975068 270)
			(size 0.519938 1.4986)
			(layers "F.Cu" "F.Mask" "F.Paste")
			(net "GND")
		)
		(pad "53" smd rect
			(at -2.050034 -19.12493 270)
			(size 0.519938 1.4986)
			(layers "F.Cu" "F.Mask" "F.Paste")
			(net "M_E_CPU0_SA_CB<1>")
		)
		(pad "54" smd rect
			(at -2.050034 -18.275046 270)
			(size 0.519938 1.4986)
			(layers "F.Cu" "F.Mask" "F.Paste")
			(net "GND")
		)
		(pad "55" smd rect
			(at -2.050034 -17.424908 270)
			(size 0.519938 1.4986)
			(layers "F.Cu" "F.Mask" "F.Paste")
			(net "M_E_CPU0_SA_DQS_DP<4>")
		)
		(pad "56" smd rect
			(at -2.050034 -16.575024 270)
			(size 0.519938 1.4986)
			(layers "F.Cu" "F.Mask" "F.Paste")
			(net "M_E_CPU0_SA_DQS_DN<4>")
		)
		(pad "57" smd rect
			(at -2.050034 -15.724886 270)
			(size 0.519938 1.4986)
			(layers "F.Cu" "F.Mask" "F.Paste")
			(net "GND")
		)
		(pad "58" smd rect
			(at -2.050034 -14.875002 270)
			(size 0.519938 1.4986)
			(layers "F.Cu" "F.Mask" "F.Paste")
			(net "M_E_CPU0_SA_CB<4>")
		)
		(pad "59" smd rect
			(at -2.050034 -14.025118 270)
			(size 0.519938 1.4986)
			(layers "F.Cu" "F.Mask" "F.Paste")
			(net "GND")
		)
		(pad "60" smd rect
			(at -2.050034 -13.17498 270)
			(size 0.519938 1.4986)
			(layers "F.Cu" "F.Mask" "F.Paste")
			(net "M_E_CPU0_SA_CB<5>")
		)
		(pad "61" smd rect
			(at -2.050034 -12.325096 270)
			(size 0.519938 1.4986)
			(layers "F.Cu" "F.Mask" "F.Paste")
			(net "GND")
		)
		(pad "62" smd rect
			(at -2.050034 -11.474958 270)
			(size 0.519938 1.4986)
			(layers "F.Cu" "F.Mask" "F.Paste")
			(net "M_E_CPU0_ALERT_N")
		)
		(pad "63" smd rect
			(at -2.050034 -10.625074 270)
			(size 0.519938 1.4986)
			(layers "F.Cu" "F.Mask" "F.Paste")
			(net "GND")
		)
		(pad "64" smd rect
			(at -2.050034 -9.774936 270)
			(size 0.519938 1.4986)
			(layers "F.Cu" "F.Mask" "F.Paste")
			(net "M_E_CPU0_SA_CS_N<0>")
		)
		(pad "65" smd rect
			(at -2.050034 -8.925052 270)
			(size 0.519938 1.4986)
			(layers "F.Cu" "F.Mask" "F.Paste")
			(net "GND")
		)
		(pad "66" smd rect
			(at -2.050034 -8.074914 270)
			(size 0.519938 1.4986)
			(layers "F.Cu" "F.Mask" "F.Paste")
			(net "M_E_CPU0_SA_CA<0>")
		)
		(pad "67" smd rect
			(at -2.050034 -7.22503 270)
			(size 0.519938 1.4986)
			(layers "F.Cu" "F.Mask" "F.Paste")
			(net "GND")
		)
		(pad "68" smd rect
			(at -2.050034 -6.374892 270)
			(size 0.519938 1.4986)
			(layers "F.Cu" "F.Mask" "F.Paste")
			(net "M_E_CPU0_SA_CA<2>")
		)
		(pad "69" smd rect
			(at -2.050034 -5.525008 270)
			(size 0.519938 1.4986)
			(layers "F.Cu" "F.Mask" "F.Paste")
			(net "GND")
		)
		(pad "70" smd rect
			(at -2.050034 -4.675124 270)
			(size 0.519938 1.4986)
			(layers "F.Cu" "F.Mask" "F.Paste")
			(net "M_E_CPU0_SA_CA<4>")
		)
		(pad "71" smd rect
			(at -2.050034 -3.824986 270)
			(size 0.519938 1.4986)
			(layers "F.Cu" "F.Mask" "F.Paste")
			(net "GND")
		)
		(pad "72" smd rect
			(at -2.050034 -2.975102 270)
			(size 0.519938 1.4986)
			(layers "F.Cu" "F.Mask" "F.Paste")
			(net "M_E_CPU0_SA_CA<6>")
		)
		(pad "73" smd rect
			(at -2.050034 -2.124964 270)
			(size 0.519938 1.4986)
			(layers "F.Cu" "F.Mask" "F.Paste")
			(net "GND")
		)
		(pad "74" smd rect
			(at -2.050034 -1.27508 270)
			(size 0.519938 1.4986)
			(layers "F.Cu" "F.Mask" "F.Paste")
			(net "M_E_CPU0_SA_PAR")
		)
		(pad "75" smd rect
			(at -2.050034 -0.424942 270)
			(size 0.519938 1.4986)
			(layers "F.Cu" "F.Mask" "F.Paste")
			(net "GND")
		)
		(pad "76" smd rect
			(at -2.050034 5.525008 270)
			(size 0.519938 1.4986)
			(layers "F.Cu" "F.Mask" "F.Paste")
			(net "M_E_CPU0_SB_CA<0>")
		)
		(pad "77" smd rect
			(at -2.050034 6.374892 270)
			(size 0.519938 1.4986)
			(layers "F.Cu" "F.Mask" "F.Paste")
			(net "GND")
		)
		(pad "78" smd rect
			(at -2.050034 7.22503 270)
			(size 0.519938 1.4986)
			(layers "F.Cu" "F.Mask" "F.Paste")
			(net "M_E_CPU0_SB_CA<2>")
		)
		(pad "79" smd rect
			(at -2.050034 8.074914 270)
			(size 0.519938 1.4986)
			(layers "F.Cu" "F.Mask" "F.Paste")
			(net "GND")
		)
		(pad "80" smd rect
			(at -2.050034 8.925052 270)
			(size 0.519938 1.4986)
			(layers "F.Cu" "F.Mask" "F.Paste")
			(net "M_E_CPU0_SB_CA<4>")
		)
		(pad "81" smd rect
			(at -2.050034 9.774936 270)
			(size 0.519938 1.4986)
			(layers "F.Cu" "F.Mask" "F.Paste")
			(net "GND")
		)
		(pad "82" smd rect
			(at -2.050034 10.625074 270)
			(size 0.519938 1.4986)
			(layers "F.Cu" "F.Mask" "F.Paste")
			(net "M_E_CPU0_SB_CA<6>")
		)
		(pad "83" smd rect
			(at -2.050034 11.474958 270)
			(size 0.519938 1.4986)
			(layers "F.Cu" "F.Mask" "F.Paste")
			(net "GND")
		)
		(pad "84" smd rect
			(at -2.050034 12.325096 270)
			(size 0.519938 1.4986)
			(layers "F.Cu" "F.Mask" "F.Paste")
			(net "M_E_CPU0_SB_CS_N<0>")
		)
		(pad "85" smd rect
			(at -2.050034 13.17498 270)
			(size 0.519938 1.4986)
			(layers "F.Cu" "F.Mask" "F.Paste")
			(net "GND")
		)
		(pad "86" smd rect
			(at -2.050034 14.025118 270)
			(size 0.519938 1.4986)
			(layers "F.Cu" "F.Mask" "F.Paste")
			(net "M_E_CPU0_SA_RSP<0>")
		)
		(pad "87" smd rect
			(at -2.050034 14.875002 270)
			(size 0.519938 1.4986)
			(layers "F.Cu" "F.Mask" "F.Paste")
			(net "M_E_CPU0_SB_RSP<0>")
		)
		(pad "88" smd rect
			(at -2.050034 15.724886 270)
			(size 0.519938 1.4986)
			(layers "F.Cu" "F.Mask" "F.Paste")
			(net "GND")
		)
		(pad "89" smd rect
			(at -2.050034 16.575024 270)
			(size 0.519938 1.4986)
			(layers "F.Cu" "F.Mask" "F.Paste")
			(net "M_E_CPU0_SB_CB<4>")
		)
		(pad "90" smd rect
			(at -2.050034 17.424908 270)
			(size 0.519938 1.4986)
			(layers "F.Cu" "F.Mask" "F.Paste")
			(net "GND")
		)
		(pad "91" smd rect
			(at -2.050034 18.275046 270)
			(size 0.519938 1.4986)
			(layers "F.Cu" "F.Mask" "F.Paste")
			(net "M_E_CPU0_SB_CB<5>")
		)
	)
)
